# TIMECARD (Time Appliance Project (Time Card)) — schematic netlist excerpt (pin names and nets, part order shuffled) for the footprints in the layout excerpt that follows; sources: Cadence DE-HDL packaged netlist, KiCad conversion of R4006-B0001-02_R01.brd

R44  RESISTOR  4.7KOHM 1%  pkg SMC_0402R_H016  page 21 : \1\ = XP5R0V_MAC ; \2\ = UNNAMED_527_POWERMOS3PNCHV1_I23
L22  FERRITEBEAD  600OHM 25%  pkg SMC_0603R_H037  page 24 : \1\ = XP3R3V_FT4232 ; \2\ = XP3R3V_VPHY

(kicad_pcb
	(version 20260206)
	(generator "pcbnew")
	(generator_version "10.0")
	(general
		(thickness 1.6)
		(legacy_teardrops no)
	)
	(paper "A4")
	(title_block
		(title "timecard-production-celestica-r4006 — R4006-B0001-02_R01.brd")
		(comment 1 "Time Appliance Project (Time Card) / footprints 808-809 of 1113")
	)
	(layers
		(0 "F.Cu" signal "TOP")
		(4 "In1.Cu" signal "L02_GND1")
		(6 "In2.Cu" signal "L03_SIG1")
		(8 "In3.Cu" signal "L04_GND2")
		(10 "In4.Cu" signal "L05_VCC1")
		(12 "In5.Cu" signal "L06_VCC2")
		(14 "In6.Cu" signal "L07_GND3")
		(16 "In7.Cu" signal "L08_SIG2")
		(18 "In8.Cu" signal "L09_GND4")
		(2 "B.Cu" signal "BOTTOM")
		(9 "F.Adhes" user "F.Adhesive")
		(11 "B.Adhes" user "B.Adhesive")
		(13 "F.Paste" user "Package Geometry/Pastemask Top")
		(15 "B.Paste" user "Package Geometry/Pastemask Bottom")
		(5 "F.SilkS" user "Ref Des/Silkscreen Top")
		(7 "B.SilkS" user "Ref Des/Silkscreen Bottom")
		(1 "F.Mask" user "Board Geometry/Soldermask Top")
		(3 "B.Mask" user "Board Geometry/Soldermask Bottom")
		(17 "Dwgs.User" user "User.Drawings")
		(19 "Cmts.User" user "User.Comments")
		(21 "Eco1.User" user "User.Eco1")
		(23 "Eco2.User" user "User.Eco2")
		(25 "Edge.Cuts" user "Board Geometry/Outline")
		(27 "Margin" user)
		(31 "F.CrtYd" user "Package Geometry/Place Bound Top")
		(29 "B.CrtYd" user "Package Geometry/Place Bound Bottom")
		(35 "F.Fab" user "Ref Des/Assembly Top")
		(33 "B.Fab" user "Ref Des/Assembly Bottom")
	)
	(footprint ""
		(layer "B.Cu")
		(at 73.914 -58.928 90)
		(property "Reference" "R44"
			(at 2.54 6.81863 270)
			(unlocked yes)
			(layer "B.SilkS")
			(effects
				(font
					(size 0.7874 0.5842)
					(thickness 0.1524)
				)
				(justify mirror)
			)
		)
		(property "Value" "VAL*"
			(at -0.02032 2.13233 90)
			(unlocked yes)
			(layer "B.Fab")
			(hide yes)
			(effects
				(font
					(size 0.7874 0.5842)
					(thickness 0.1524)
				)
				(justify mirror)
			)
		)
		(property "Tolerance" "TOL*"
			(at -0.044704 3.05435 90)
			(unlocked yes)
			(layer "Cmts.User")
			(hide yes)
			(effects
				(font
					(size 0.7874 0.5842)
					(thickness 0.1524)
				)
				(justify mirror)
			)
		)
		(property "User Part Number" "PARTNUM*"
			(at -0.02032 4.024884 90)
			(unlocked yes)
			(layer "Cmts.User")
			(hide yes)
			(effects
				(font
					(size 0.7874 0.5842)
					(thickness 0.1524)
				)
				(justify mirror)
			)
		)
		(property "Device Type" "RESISTOR-G155-14701-01,4.7KOHMA"
			(at -0.008382 1.210564 90)
			(unlocked yes)
			(layer "B.Fab")
			(hide yes)
			(effects
				(font
					(size 0.7874 0.5842)
					(thickness 0.1524)
				)
				(justify mirror)
			)
		)
		(duplicate_pad_numbers_are_jumpers no)
		(fp_line
			(start 1.143 -0.5588)
			(end 1.143 0.5588)
			(stroke
				(width 0.1)
				(type default)
			)
			(layer "B.SilkS")
		)
		(fp_line
			(start -1.143 -0.5588)
			(end 1.143 -0.5588)
			(stroke
				(width 0.1)
				(type default)
			)
			(layer "B.SilkS")
		)
		(fp_line
			(start 1.143 0.5588)
			(end -1.143 0.5588)
			(stroke
				(width 0.1)
				(type default)
			)
			(layer "B.SilkS")
		)
		(fp_line
			(start -1.143 0.5588)
			(end -1.143 -0.5588)
			(stroke
				(width 0.1)
				(type default)
			)
			(layer "B.SilkS")
		)
		(fp_rect
			(start 1.143 0.5588)
			(end -1.143 -0.5588)
			(stroke
				(width 0)
				(type default)
			)
			(fill no)
			(layer "B.CrtYd")
		)
		(fp_line
			(start 0.508 -0.3048)
			(end 0.508 0.3048)
			(stroke
				(width 0.1)
				(type default)
			)
			(layer "B.Fab")
		)
		(fp_line
			(start -0.508 -0.3048)
			(end 0.508 -0.3048)
			(stroke
				(width 0.1)
				(type default)
			)
			(layer "B.Fab")
		)
		(fp_line
			(start 0.508 0.3048)
			(end -0.508 0.3048)
			(stroke
				(width 0.1)
				(type default)
			)
			(layer "B.Fab")
		)
		(fp_line
			(start -0.508 0.3048)
			(end -0.508 -0.3048)
			(stroke
				(width 0.1)
				(type default)
			)
			(layer "B.Fab")
		)
		(pad "1" smd rect
			(at 0.5334 0 270)
			(size 0.7112 0.6096)
			(layers "B.Cu" "B.Mask" "B.Paste")
			(net "XP5R0V_MAC")
		)
		(pad "2" smd rect
			(at -0.5334 0 270)
			(size 0.7112 0.6096)
			(layers "B.Cu" "B.Mask" "B.Paste")
			(net "UNNAMED_527_POWERMOS3PNCHV1_I23")
		)
		(zone
			(layer "B.Cu")
			(hatch none 0.5)
			(connect_pads
				(clearance 0)
			)
			(min_thickness 0.25)
			(keepout
				(tracks allowed)
				(vias not_allowed)
				(pads allowed)
				(copperpour not_allowed)
				(footprints allowed)
			)
			(placement
				(enabled no)
				(sheetname "")
			)
			(fill
				(thermal_gap 0.5)
				(thermal_bridge_width 0.5)
				(island_removal_mode 0)
			)
			(polygon
				(pts
					(xy 74.2188 -59.0042) (xy 73.6092 -59.0042) (xy 73.6092 -58.8518) (xy 74.2188 -58.8518)
				)
			)
		)
		(zone
			(layer "B.Cu")
			(hatch none 0.5)
			(connect_pads
				(clearance 0)
			)
			(min_thickness 0.25)
			(keepout
				(tracks not_allowed)
				(vias allowed)
				(pads allowed)
				(copperpour not_allowed)
				(footprints allowed)
			)
			(placement
				(enabled no)
				(sheetname "")
			)
			(fill
				(thermal_gap 0.5)
				(thermal_bridge_width 0.5)
				(island_removal_mode 0)
			)
			(polygon
				(pts
					(xy 74.2188 -59.0042) (xy 73.6092 -59.0042) (xy 73.6092 -58.8518) (xy 74.2188 -58.8518)
				)
			)
		)
	)
	(footprint ""
		(layer "B.Cu")
		(at 33.528 -90.805 90)
		(property "Reference" "L22"
			(at 3.175 -0.03937 270)
			(unlocked yes)
			(layer "B.SilkS")
			(effects
				(font
					(size 0.7874 0.5842)
					(thickness 0.1524)
				)
				(justify mirror)
			)
		)
		(property "Value" "VAL*"
			(at -0.014732 2.526538 90)
			(unlocked yes)
			(layer "B.Fab")
			(hide yes)
			(effects
				(font
					(size 0.7874 0.5842)
					(thickness 0.000001)
				)
				(justify mirror)
			)
		)
		(property "Tolerance" "TOL*"
			(at -0.014732 3.503676 90)
			(unlocked yes)
			(layer "Cmts.User")
			(hide yes)
			(effects
				(font
					(size 0.7874 0.5842)
					(thickness 0.000001)
				)
				(justify mirror)
			)
		)
		(property "User Part Number" "PARTNUM*"
			(at -0.02794 4.480814 90)
			(unlocked yes)
			(layer "Cmts.User")
			(hide yes)
			(effects
				(font
					(size 0.7874 0.5842)
					(thickness 0.000001)
				)
				(justify mirror)
			)
		)
		(property "Device Type" "FERRITEBEAD-G191-10097-01,600OA"
			(at -0.014732 1.600708 90)
			(unlocked yes)
			(layer "B.Fab")
			(hide yes)
			(effects
				(font
					(size 0.7874 0.5842)
					(thickness 0.000001)
				)
				(justify mirror)
			)
		)
		(duplicate_pad_numbers_are_jumpers no)
		(fp_line
			(start 1.3208 -0.7112)
			(end -1.3208 -0.7112)
			(stroke
				(width 0.1)
				(type default)
			)
			(layer "B.SilkS")
		)
		(fp_line
			(start -1.3208 -0.7112)
			(end -1.3208 0.7112)
			(stroke
				(width 0.1)
				(type default)
			)
			(layer "B.SilkS")
		)
		(fp_line
			(start 1.3208 0.7112)
			(end 1.3208 -0.7112)
			(stroke
				(width 0.1)
				(type default)
			)
			(layer "B.SilkS")
		)
		(fp_line
			(start -1.3208 0.7112)
			(end 1.3208 0.7112)
			(stroke
				(width 0.1)
				(type default)
			)
			(layer "B.SilkS")
		)
		(fp_rect
			(start 1.3208 0.7112)
			(end -1.3208 -0.7112)
			(stroke
				(width 0)
				(type default)
			)
			(fill no)
			(layer "B.CrtYd")
		)
		(fp_line
			(start 0.8128 -0.4572)
			(end -0.8128 -0.4572)
			(stroke
				(width 0.1)
				(type default)
			)
			(layer "B.Fab")
		)
		(fp_line
			(start -0.8128 -0.4572)
			(end -0.8128 0.4572)
			(stroke
				(width 0.1)
				(type default)
			)
			(layer "B.Fab")
		)
		(fp_line
			(start 0.8128 0.4572)
			(end 0.8128 -0.4572)
			(stroke
				(width 0.1)
				(type default)
			)
			(layer "B.Fab")
		)
		(fp_line
			(start -0.8128 0.4572)
			(end 0.8128 0.4572)
			(stroke
				(width 0.1)
				(type default)
			)
			(layer "B.Fab")
		)
		(pad "1" smd rect
			(at 0.6858 0 270)
			(size 0.762 0.8636)
			(layers "B.Cu" "B.Mask" "B.Paste")
			(net "XP3R3V_FT4232")
		)
		(pad "2" smd rect
			(at -0.6858 0 270)
			(size 0.762 0.8636)
			(layers "B.Cu" "B.Mask" "B.Paste")
			(net "XP3R3V_VPHY")
		)
		(zone
			(layer "B.Cu")
			(hatch none 0.5)
			(connect_pads
				(clearance 0)
			)
			(min_thickness 0.25)
			(keepout
				(tracks allowed)
				(vias not_allowed)
				(pads allowed)
				(copperpour not_allowed)
				(footprints allowed)
			)
			(placement
				(enabled no)
				(sheetname "")
			)
			(fill
				(thermal_gap 0.5)
				(thermal_bridge_width 0.5)
				(island_removal_mode 0)
			)
			(polygon
				(pts
					(xy 33.9852 -90.9574) (xy 33.0708 -90.9574) (xy 33.0708 -90.6526) (xy 33.9852 -90.6526)
				)
			)
		)
		(zone
			(layer "B.Cu")
			(hatch none 0.5)
			(connect_pads
				(clearance 0)
			)
			(min_thickness 0.25)
			(keepout
				(tracks not_allowed)
				(vias allowed)
				(pads allowed)
				(copperpour not_allowed)
				(footprints allowed)
			)
			(placement
				(enabled no)
				(sheetname "")
			)
			(fill
				(thermal_gap 0.5)
				(thermal_bridge_width 0.5)
				(island_removal_mode 0)
			)
			(polygon
				(pts
					(xy 33.9852 -90.9574) (xy 33.0708 -90.9574) (xy 33.0708 -90.6526) (xy 33.9852 -90.6526)
				)
			)
		)
	)
)
